(kicad_pcb
	(version 20260206)
	(generator "pcbnew")
	(generator_version "10.0")
	(general
		(thickness 1.6)
		(legacy_teardrops no)
	)
	(paper "A4")
	(title_block
		(title "Bryce Canyon_R.DPB_16317-1_OCP.brd")
		(comment 1 "Bryce Canyon / footprints 1022-1028 of 2099")
	)
	(layers
		(0 "F.Cu" signal "TOP")
		(4 "In1.Cu" signal "L2GND")
		(6 "In2.Cu" signal "L3")
		(8 "In3.Cu" signal "L4VCC")
		(10 "In4.Cu" signal "L5VCC")
		(12 "In5.Cu" signal "L6")
		(14 "In6.Cu" signal "L7GND")
		(2 "B.Cu" signal "BOTTOM")
		(9 "F.Adhes" user "F.Adhesive")
		(11 "B.Adhes" user "B.Adhesive")
		(13 "F.Paste" user "Package Geometry/Pastemask Top")
		(15 "B.Paste" user "Package Geometry/Pastemask Bottom")
		(5 "F.SilkS" user "Ref Des/Silkscreen Top")
		(7 "B.SilkS" user "Ref Des/Silkscreen Bottom")
		(1 "F.Mask" user "Board Geometry/Soldermask Top")
		(3 "B.Mask" user "Board Geometry/Soldermask Bottom")
		(17 "Dwgs.User" user "User.Drawings")
		(19 "Cmts.User" user "User.Comments")
		(21 "Eco1.User" user "User.Eco1")
		(23 "Eco2.User" user "User.Eco2")
		(25 "Edge.Cuts" user "Board Geometry/Outline")
		(27 "Margin" user)
		(31 "F.CrtYd" user "Package Geometry/Place Bound Top")
		(29 "B.CrtYd" user "Package Geometry/Place Bound Bottom")
		(35 "F.Fab" user "Ref Des/Assembly Top")
		(33 "B.Fab" user "Ref Des/Assembly Bottom")
	)
	(footprint ""
		(layer "F.Cu")
		(at 321.7164 -31.6484)
		(property "Reference" "C427"
			(at 0 0 0)
			(layer "F.SilkS")
			(hide yes)
			(effects
				(font
					(size 1.27 1.27)
				)
			)
		)
		(property "Value" "SCD01U50V2KX-1GP"
			(at 1.1811 -2.7051 0)
			(unlocked yes)
			(layer "F.Fab")
			(hide yes)
			(effects
				(font
					(size 1.016 1.016)
					(thickness 0.1524)
				)
			)
		)
		(property "Device Type" "C402H22"
			(at 1.1811 -4.2291 0)
			(unlocked yes)
			(layer "F.Fab")
			(hide yes)
			(effects
				(font
					(size 1.016 1.016)
					(thickness 0.1524)
				)
			)
		)
		(duplicate_pad_numbers_are_jumpers no)
		(fp_rect
			(start -0.4318 0.9525)
			(end 0.4318 -0.9525)
			(stroke
				(width 0)
				(type default)
			)
			(fill no)
			(layer "F.CrtYd")
		)
		(fp_rect
			(start -0.4318 0.9525)
			(end 0.4318 -0.9525)
			(stroke
				(width 0)
				(type default)
			)
			(fill no)
			(layer "F.Fab")
		)
		(pad "1" smd custom
			(at 0 -0.4445)
			(size 0.1524 0.1524)
			(layers "F.Cu" "F.Mask" "F.Paste")
			(net "HDD_PRSNT_30")
			(options
				(clearance outline)
				(anchor circle)
			)
			(primitives
				(gr_poly
					(pts
						(arc
							(start 0.3048 -0.2032)
							(mid 0.275042 -0.275042)
							(end 0.2032 -0.3048)
						)
						(arc
							(start -0.2032 -0.3048)
							(mid -0.275042 -0.275042)
							(end -0.3048 -0.2032)
						)
						(arc
							(start -0.3048 0.2032)
							(mid -0.275042 0.275042)
							(end -0.2032 0.3048)
						)
						(arc
							(start 0.2032 0.3048)
							(mid 0.275042 0.275042)
							(end 0.3048 0.2032)
						)
					)
					(width 0)
					(fill yes)
				)
			)
		)
		(pad "2" smd custom
			(at 0 0.4445)
			(size 0.1524 0.1524)
			(layers "F.Cu" "F.Mask" "F.Paste")
			(net "GND")
			(options
				(clearance outline)
				(anchor circle)
			)
			(primitives
				(gr_poly
					(pts
						(arc
							(start 0.3048 -0.2032)
							(mid 0.275042 -0.275042)
							(end 0.2032 -0.3048)
						)
						(arc
							(start -0.2032 -0.3048)
							(mid -0.275042 -0.275042)
							(end -0.3048 -0.2032)
						)
						(arc
							(start -0.3048 0.2032)
							(mid -0.275042 0.275042)
							(end -0.2032 0.3048)
						)
						(arc
							(start 0.2032 0.3048)
							(mid 0.275042 0.275042)
							(end 0.3048 0.2032)
						)
					)
					(width 0)
					(fill yes)
				)
			)
		)
	)
	(footprint ""
		(layer "F.Cu")
		(at 78.359 -248.158 180)
		(property "Reference" "R202"
			(at 0 0 180)
			(layer "F.SilkS")
			(hide yes)
			(effects
				(font
					(size 1.27 1.27)
				)
			)
		)
		(property "Value" "200KR2F-L-GP"
			(at 0.064008 -3.993896 180)
			(unlocked yes)
			(layer "F.Fab")
			(hide yes)
			(effects
				(font
					(size 1.016 1.016)
					(thickness 0.1524)
				)
			)
		)
		(property "Device Type" "R402H16"
			(at 0.064008 -5.517896 180)
			(unlocked yes)
			(layer "F.Fab")
			(hide yes)
			(effects
				(font
					(size 1.016 1.016)
					(thickness 0.1524)
				)
			)
		)
		(duplicate_pad_numbers_are_jumpers no)
		(fp_line
			(start 0.508 -0.9398)
			(end -0.508 -0.9398)
			(stroke
				(width 0.1524)
				(type default)
			)
			(layer "F.SilkS")
		)
		(fp_line
			(start -0.508 -0.9398)
			(end -0.508 0.9398)
			(stroke
				(width 0.1524)
				(type default)
			)
			(layer "F.SilkS")
		)
		(fp_rect
			(start -0.508 0.9398)
			(end 0.508 -0.9398)
			(stroke
				(width 0)
				(type default)
			)
			(fill no)
			(layer "F.CrtYd")
		)
		(fp_rect
			(start -0.508 0.9398)
			(end 0.508 -0.9398)
			(stroke
				(width 0)
				(type default)
			)
			(fill no)
			(layer "F.Fab")
		)
		(pad "1" smd custom
			(at 0 -0.4445 180)
			(size 0.1397 0.1397)
			(layers "F.Cu" "F.Mask" "F.Paste")
			(net "SW_HDD_R2")
			(options
				(clearance outline)
				(anchor circle)
			)
			(primitives
				(gr_poly
					(pts
						(arc
							(start -0.1778 -0.2794)
							(mid -0.249642 -0.249642)
							(end -0.2794 -0.1778)
						)
						(arc
							(start -0.2794 0.1778)
							(mid -0.249642 0.249642)
							(end -0.1778 0.2794)
						)
						(arc
							(start 0.1778 0.2794)
							(mid 0.249642 0.249642)
							(end 0.2794 0.1778)
						)
						(arc
							(start 0.2794 -0.1778)
							(mid 0.249642 -0.249642)
							(end 0.1778 -0.2794)
						)
					)
					(width 0)
					(fill yes)
				)
			)
		)
		(pad "2" smd custom
			(at 0 0.4445 180)
			(size 0.1397 0.1397)
			(layers "F.Cu" "F.Mask" "F.Paste")
			(net "SW_HDD_N2")
			(options
				(clearance outline)
				(anchor circle)
			)
			(primitives
				(gr_poly
					(pts
						(arc
							(start -0.1778 -0.2794)
							(mid -0.249642 -0.249642)
							(end -0.2794 -0.1778)
						)
						(arc
							(start -0.2794 0.1778)
							(mid -0.249642 0.249642)
							(end -0.1778 0.2794)
						)
						(arc
							(start 0.1778 0.2794)
							(mid 0.249642 0.249642)
							(end 0.2794 0.1778)
						)
						(arc
							(start 0.2794 -0.1778)
							(mid 0.249642 -0.249642)
							(end 0.1778 -0.2794)
						)
					)
					(width 0)
					(fill yes)
				)
			)
		)
	)
	(footprint ""
		(layer "F.Cu")
		(at 398.018 -253.873 -90)
		(property "Reference" "Q30"
			(at 0 0 270)
			(layer "F.SilkS")
			(hide yes)
			(effects
				(font
					(size 1.27 1.27)
				)
			)
		)
		(property "Value" "AO4406AL-GP"
			(at -3.707384 -1.5367 270)
			(unlocked yes)
			(layer "F.Fab")
			(hide yes)
			(effects
				(font
					(size 1.016 1.016)
					(thickness 0.1524)
				)
			)
		)
		(property "Device Type" "SOIC8H69"
			(at -3.707384 -3.0607 270)
			(unlocked yes)
			(layer "F.Fab")
			(hide yes)
			(effects
				(font
					(size 1.016 1.016)
					(thickness 0.1524)
				)
			)
		)
		(duplicate_pad_numbers_are_jumpers no)
		(fp_line
			(start -2.6289 3.4417)
			(end -2.6289 1.4732)
			(stroke
				(width 0.381)
				(type default)
			)
			(layer "F.SilkS")
		)
		(fp_line
			(start -2.7432 1.4224)
			(end -2.6416 1.4224)
			(stroke
				(width 0.1524)
				(type default)
			)
			(layer "F.SilkS")
		)
		(fp_line
			(start -2.7432 1.4224)
			(end 2.1336 1.4224)
			(stroke
				(width 0.1524)
				(type default)
			)
			(layer "F.SilkS")
		)
		(fp_line
			(start 2.1336 1.4224)
			(end 2.1336 -1.4224)
			(stroke
				(width 0.1524)
				(type default)
			)
			(layer "F.SilkS")
		)
		(fp_line
			(start -2.1844 -0.0508)
			(end -2.7178 0.508)
			(stroke
				(width 0.1524)
				(type default)
			)
			(layer "F.SilkS")
		)
		(fp_line
			(start -2.7178 -0.508)
			(end -2.1844 -0.0508)
			(stroke
				(width 0.1524)
				(type default)
			)
			(layer "F.SilkS")
		)
		(fp_line
			(start -2.7432 -1.4224)
			(end -2.7432 1.4224)
			(stroke
				(width 0.1524)
				(type default)
			)
			(layer "F.SilkS")
		)
		(fp_line
			(start 2.1336 -1.4224)
			(end -2.7432 -1.4224)
			(stroke
				(width 0.1524)
				(type default)
			)
			(layer "F.SilkS")
		)
		(fp_poly
			(pts
				(xy -2.2098 -1.4224) (xy -2.2098 1.4224) (xy 2.2098 1.4224) (xy 2.2098 -1.4224)
			)
			(stroke
				(width 0)
				(type default)
			)
			(fill yes)
			(layer "F.SilkS")
		)
		(fp_rect
			(start -2.450084 2.999994)
			(end 2.450084 -2.999994)
			(stroke
				(width 0)
				(type default)
			)
			(fill no)
			(layer "F.CrtYd")
		)
		(fp_poly
			(pts
				(xy -2.8194 3.6322) (xy -2.8194 -3.6322) (xy 2.8194 -3.6322) (xy 2.8194 1.18364) (xy 2.450084 1.18364)
				(xy 2.450084 -2.999994) (xy -2.450084 -2.999994) (xy -2.450084 2.999994) (xy 2.450084 2.999994)
				(xy 2.450084 1.18618) (xy 2.8194 1.18618) (xy 2.8194 3.6322)
			)
			(stroke
				(width 0)
				(type default)
			)
			(fill no)
			(layer "F.CrtYd")
		)
		(fp_rect
			(start -2.8194 3.6322)
			(end 2.8194 -3.6322)
			(stroke
				(width 0)
				(type default)
			)
			(fill no)
			(layer "F.Fab")
		)
		(pad "1" smd rect
			(at -1.905 2.54 270)
			(size 0.635 1.651)
			(layers "F.Cu" "F.Mask" "F.Paste")
			(net "P5V_HDD8")
		)
		(pad "2" smd rect
			(at -0.635 2.54 270)
			(size 0.635 1.651)
			(layers "F.Cu" "F.Mask" "F.Paste")
			(net "P5V_HDD8")
		)
		(pad "3" smd rect
			(at 0.635 2.54 270)
			(size 0.635 1.651)
			(layers "F.Cu" "F.Mask" "F.Paste")
			(net "P5V_HDD8")
		)
		(pad "4" smd rect
			(at 1.905 2.54 270)
			(size 0.635 1.651)
			(layers "F.Cu" "F.Mask" "F.Paste")
			(net "SW_HDD_P8")
		)
		(pad "5" smd rect
			(at 1.905 -2.54 270)
			(size 0.635 1.651)
			(layers "F.Cu" "F.Mask" "F.Paste")
			(net "P5V_B_3")
		)
		(pad "6" smd rect
			(at 0.635 -2.54 270)
			(size 0.635 1.651)
			(layers "F.Cu" "F.Mask" "F.Paste")
			(net "P5V_B_3")
		)
		(pad "7" smd rect
			(at -0.635 -2.54 270)
			(size 0.635 1.651)
			(layers "F.Cu" "F.Mask" "F.Paste")
			(net "P5V_B_3")
		)
		(pad "8" smd rect
			(at -1.905 -2.54 270)
			(size 0.635 1.651)
			(layers "F.Cu" "F.Mask" "F.Paste")
			(net "P5V_B_3")
		)
	)
	(footprint ""
		(layer "F.Cu")
		(at 332.232 -10.16 180)
		(property "Reference" "R768"
			(at 0 0 180)
			(layer "F.SilkS")
			(hide yes)
			(effects
				(font
					(size 1.27 1.27)
				)
			)
		)
		(property "Value" "1KR2F-3-GP"
			(at 0.064008 -3.993896 180)
			(unlocked yes)
			(layer "F.Fab")
			(hide yes)
			(effects
				(font
					(size 1.016 1.016)
					(thickness 0.1524)
				)
			)
		)
		(property "Device Type" "R402H16"
			(at 0.064008 -5.517896 180)
			(unlocked yes)
			(layer "F.Fab")
			(hide yes)
			(effects
				(font
					(size 1.016 1.016)
					(thickness 0.1524)
				)
			)
		)
		(duplicate_pad_numbers_are_jumpers no)
		(fp_line
			(start 0.508 -0.9398)
			(end -0.508 -0.9398)
			(stroke
				(width 0.1524)
				(type default)
			)
			(layer "F.SilkS")
		)
		(fp_line
			(start -0.508 -0.9398)
			(end -0.508 0.9398)
			(stroke
				(width 0.1524)
				(type default)
			)
			(layer "F.SilkS")
		)
		(fp_rect
			(start -0.508 0.9398)
			(end 0.508 -0.9398)
			(stroke
				(width 0)
				(type default)
			)
			(fill no)
			(layer "F.CrtYd")
		)
		(fp_rect
			(start -0.508 0.9398)
			(end 0.508 -0.9398)
			(stroke
				(width 0)
				(type default)
			)
			(fill no)
			(layer "F.Fab")
		)
		(pad "1" smd custom
			(at 0 -0.4445 180)
			(size 0.1397 0.1397)
			(layers "F.Cu" "F.Mask" "F.Paste")
			(net "P3V3_STBY_B")
			(options
				(clearance outline)
				(anchor circle)
			)
			(primitives
				(gr_poly
					(pts
						(arc
							(start -0.1778 -0.2794)
							(mid -0.249642 -0.249642)
							(end -0.2794 -0.1778)
						)
						(arc
							(start -0.2794 0.1778)
							(mid -0.249642 0.249642)
							(end -0.1778 0.2794)
						)
						(arc
							(start 0.1778 0.2794)
							(mid 0.249642 0.249642)
							(end 0.2794 0.1778)
						)
						(arc
							(start 0.2794 -0.1778)
							(mid 0.249642 -0.249642)
							(end 0.1778 -0.2794)
						)
					)
					(width 0)
					(fill yes)
				)
			)
		)
		(pad "2" smd custom
			(at 0 0.4445 180)
			(size 0.1397 0.1397)
			(layers "F.Cu" "F.Mask" "F.Paste")
			(net "SW_PWR_R_HDD30")
			(options
				(clearance outline)
				(anchor circle)
			)
			(primitives
				(gr_poly
					(pts
						(arc
							(start -0.1778 -0.2794)
							(mid -0.249642 -0.249642)
							(end -0.2794 -0.1778)
						)
						(arc
							(start -0.2794 0.1778)
							(mid -0.249642 0.249642)
							(end -0.1778 0.2794)
						)
						(arc
							(start 0.1778 0.2794)
							(mid 0.249642 0.249642)
							(end 0.2794 0.1778)
						)
						(arc
							(start 0.2794 -0.1778)
							(mid 0.249642 -0.249642)
							(end 0.1778 -0.2794)
						)
					)
					(width 0)
					(fill yes)
				)
			)
		)
	)
	(footprint ""
		(layer "F.Cu")
		(at 382.315974 -269.705074)
		(property "Reference" "TP61"
			(at 0 0 0)
			(layer "F.SilkS")
			(hide yes)
			(effects
				(font
					(size 1.27 1.27)
				)
			)
		)
		(property "Value" "*"
			(at -0.0508 -1.6764 0)
			(unlocked yes)
			(layer "F.Fab")
			(hide yes)
			(effects
				(font
					(size 1.016 1.016)
					(thickness 0.1524)
				)
			)
		)
		(property "Device Type" "TPAD32"
			(at -0.0508 -3.2004 0)
			(unlocked yes)
			(layer "F.Fab")
			(hide yes)
			(effects
				(font
					(size 1.016 1.016)
					(thickness 0.1524)
				)
			)
		)
		(duplicate_pad_numbers_are_jumpers no)
		(fp_poly
			(pts
				(arc
					(start 0.4064 0)
					(mid -0.4064 0)
					(end 0.4064 0)
				)
			)
			(stroke
				(width 0)
				(type default)
			)
			(fill no)
			(layer "F.CrtYd")
		)
		(fp_poly
			(pts
				(arc
					(start 0.7112 0)
					(mid -0.7112 0)
					(end 0.7112 0)
				)
			)
			(stroke
				(width 0)
				(type default)
			)
			(fill no)
			(layer "F.Fab")
		)
		(pad "1" smd circle
			(at 0 0)
			(size 0.8128 0.8128)
			(layers "F.Cu" "F.Mask" "F.Paste")
			(net "ACT_HDD_8")
		)
	)
	(footprint ""
		(layer "F.Cu")
		(at 241.554 -230.632 -90)
		(property "Reference" "Q33"
			(at 0 0 270)
			(layer "F.SilkS")
			(hide yes)
			(effects
				(font
					(size 1.27 1.27)
				)
			)
		)
		(property "Value" "SSM3K324R-GP"
			(at 0.127 -8.9662 270)
			(unlocked yes)
			(layer "F.Fab")
			(hide yes)
			(effects
				(font
					(size 1.016 1.016)
					(thickness 0.1524)
				)
			)
		)
		(property "Device Type" "SOT23DGS2D4H35"
			(at 0.127 -10.4902 270)
			(unlocked yes)
			(layer "F.Fab")
			(hide yes)
			(effects
				(font
					(size 1.016 1.016)
					(thickness 0.1524)
				)
			)
		)
		(duplicate_pad_numbers_are_jumpers no)
		(fp_line
			(start -1.651 1.778)
			(end 1.651 1.778)
			(stroke
				(width 0.1524)
				(type default)
			)
			(layer "F.SilkS")
		)
		(fp_line
			(start 1.651 1.778)
			(end 1.651 -1.778)
			(stroke
				(width 0.1524)
				(type default)
			)
			(layer "F.SilkS")
		)
		(fp_line
			(start -1.651 -1.778)
			(end -1.651 1.778)
			(stroke
				(width 0.1524)
				(type default)
			)
			(layer "F.SilkS")
		)
		(fp_line
			(start 1.651 -1.778)
			(end -1.651 -1.778)
			(stroke
				(width 0.1524)
				(type default)
			)
			(layer "F.SilkS")
		)
		(fp_poly
			(pts
				(xy -1.778 1.8796) (xy -1.778 -1.8796) (xy 1.778 -1.8796) (xy 1.778 1.8796)
			)
			(stroke
				(width 0)
				(type default)
			)
			(fill no)
			(layer "F.CrtYd")
		)
		(fp_poly
			(pts
				(xy -1.778 1.8796) (xy -1.778 -1.8796) (xy 1.778 -1.8796) (xy 1.778 1.8796)
			)
			(stroke
				(width 0)
				(type default)
			)
			(fill no)
			(layer "F.Fab")
		)
		(pad "D" smd custom
			(at 0 -0.9525 270)
			(size 0.1905 0.1905)
			(layers "F.Cu" "F.Mask" "F.Paste")
			(net "P3V3_STBY_B")
			(options
				(clearance outline)
				(anchor circle)
			)
			(primitives
				(gr_poly
					(pts
						(arc
							(start -0.1778 0.5715)
							(mid -0.321484 0.511984)
							(end -0.381 0.3683)
						)
						(arc
							(start -0.381 -0.3683)
							(mid -0.321484 -0.511984)
							(end -0.1778 -0.5715)
						)
						(arc
							(start 0.1778 -0.5715)
							(mid 0.321484 -0.511984)
							(end 0.381 -0.3683)
						)
						(arc
							(start 0.381 0.3683)
							(mid 0.321484 0.511984)
							(end 0.1778 0.5715)
						)
					)
					(width 0)
					(fill yes)
				)
			)
		)
		(pad "G" smd custom
			(at -0.98425 0.9525 270)
			(size 0.1905 0.1905)
			(layers "F.Cu" "F.Mask" "F.Paste")
			(net "SCC_FULL_PWR_EN_5V")
			(options
				(clearance outline)
				(anchor circle)
			)
			(primitives
				(gr_poly
					(pts
						(arc
							(start -0.1778 0.5715)
							(mid -0.321484 0.511984)
							(end -0.381 0.3683)
						)
						(arc
							(start -0.381 -0.3683)
							(mid -0.321484 -0.511984)
							(end -0.1778 -0.5715)
						)
						(arc
							(start 0.1778 -0.5715)
							(mid 0.321484 -0.511984)
							(end 0.381 -0.3683)
						)
						(arc
							(start 0.381 0.3683)
							(mid 0.321484 0.511984)
							(end 0.1778 0.5715)
						)
					)
					(width 0)
					(fill yes)
				)
			)
		)
		(pad "S" smd custom
			(at 0.98425 0.9525 270)
			(size 0.1905 0.1905)
			(layers "F.Cu" "F.Mask" "F.Paste")
			(net "GPIO_VCC_U10")
			(options
				(clearance outline)
				(anchor circle)
			)
			(primitives
				(gr_poly
					(pts
						(arc
							(start -0.1778 0.5715)
							(mid -0.321484 0.511984)
							(end -0.381 0.3683)
						)
						(arc
							(start -0.381 -0.3683)
							(mid -0.321484 -0.511984)
							(end -0.1778 -0.5715)
						)
						(arc
							(start 0.1778 -0.5715)
							(mid 0.321484 -0.511984)
							(end 0.381 -0.3683)
						)
						(arc
							(start 0.381 0.3683)
							(mid 0.321484 0.511984)
							(end 0.1778 0.5715)
						)
					)
					(width 0)
					(fill yes)
				)
			)
		)
	)
	(footprint ""
		(layer "F.Cu")
		(at 416.284664 -14.660626 -90)
		(property "Reference" "C458"
			(at 0 0 270)
			(layer "F.SilkS")
			(hide yes)
			(effects
				(font
					(size 1.27 1.27)
				)
			)
		)
		(property "Value" "SCD01U16V1KX-GP"
			(at -2.8321 -1.7399 270)
			(unlocked yes)
			(layer "F.Fab")
			(hide yes)
			(effects
				(font
					(size 1.016 1.016)
					(thickness 0.1524)
				)
			)
		)
		(property "Device Type" "C0201H13"
			(at -2.8321 -3.2639 270)
			(unlocked yes)
			(layer "F.Fab")
			(hide yes)
			(effects
				(font
					(size 1.016 1.016)
					(thickness 0.1524)
				)
			)
		)
		(duplicate_pad_numbers_are_jumpers no)
		(fp_rect
			(start -0.2794 0.6477)
			(end 0.2794 -0.6477)
			(stroke
				(width 0)
				(type default)
			)
			(fill no)
			(layer "F.CrtYd")
		)
		(fp_rect
			(start -0.2794 0.6477)
			(end 0.2794 -0.6477)
			(stroke
				(width 0)
				(type default)
			)
			(fill no)
			(layer "F.Fab")
		)
		(pad "1" smd custom
			(at 0 -0.2794 270)
			(size 0.0762 0.0762)
			(layers "F.Cu" "F.Mask" "F.Paste")
			(net "SAS_HDD_RX_P33")
			(options
				(clearance outline)
				(anchor circle)
			)
			(primitives
				(gr_poly
					(pts
						(arc
							(start 0.1524 -0.127)
							(mid 0.137521 -0.162921)
							(end 0.1016 -0.1778)
						)
						(arc
							(start -0.1016 -0.1778)
							(mid -0.137521 -0.162921)
							(end -0.1524 -0.127)
						)
						(arc
							(start -0.1524 0.127)
							(mid -0.137521 0.162921)
							(end -0.1016 0.1778)
						)
						(arc
							(start 0.1016 0.1778)
							(mid 0.137521 0.162921)
							(end 0.1524 0.127)
						)
					)
					(width 0)
					(fill yes)
				)
			)
		)
		(pad "2" smd custom
			(at 0 0.2794 270)
			(size 0.0762 0.0762)
			(layers "F.Cu" "F.Mask" "F.Paste")
			(net "PHY_SCC_B_TO_DRV_B_33_DP")
			(options
				(clearance outline)
				(anchor circle)
			)
			(primitives
				(gr_poly
					(pts
						(arc
							(start 0.1524 -0.127)
							(mid 0.137521 -0.162921)
							(end 0.1016 -0.1778)
						)
						(arc
							(start -0.1016 -0.1778)
							(mid -0.137521 -0.162921)
							(end -0.1524 -0.127)
						)
						(arc
							(start -0.1524 0.127)
							(mid -0.137521 0.162921)
							(end -0.1016 0.1778)
						)
						(arc
							(start 0.1016 0.1778)
							(mid 0.137521 0.162921)
							(end 0.1524 0.127)
						)
					)
					(width 0)
					(fill yes)
				)
			)
		)
	)
)
